# S9S_MB_2U (Grand Teton) — schematic netlist excerpt (pin names and nets, part order shuffled) for the footprints in the layout excerpt that follows; sources: Cadence DE-HDL packaged netlist, KiCad conversion of 03242023_DA0F0TMBIJ0_F0T_Motherboard_J_brd_V01_OCP.brd

C991  Q_CAP  10UF 6.3V 20% X6S  pkg C0402  page 74 : A = PVCCIN_CPU0 ; B = GND
R3276  Q_RES  1K 1% EMPTY  pkg 0402LF  page 166 : A = FM_P2E_FGA ; B = GND

(kicad_pcb
	(version 20260206)
	(generator "pcbnew")
	(generator_version "10.0")
	(general
		(thickness 1.6)
		(legacy_teardrops no)
	)
	(paper "A4")
	(title_block
		(title "03242023_DA0F0TMBIJ0_F0T_Motherboard_J_brd_V01_OCP.brd")
		(comment 1 "Grand Teton / footprints 3123-3124 of 6105")
	)
	(layers
		(0 "F.Cu" signal "TOP")
		(4 "In1.Cu" signal "GND")
		(6 "In2.Cu" signal "IN1")
		(8 "In3.Cu" signal "GND1")
		(10 "In4.Cu" signal "IN2")
		(12 "In5.Cu" signal "GND2")
		(14 "In6.Cu" signal "IN3")
		(16 "In7.Cu" signal "GND3")
		(18 "In8.Cu" signal "VCC")
		(20 "In9.Cu" signal "VCC1")
		(22 "In10.Cu" signal "GND4")
		(24 "In11.Cu" signal "IN4")
		(26 "In12.Cu" signal "GND5")
		(28 "In13.Cu" signal "IN5")
		(30 "In14.Cu" signal "GND6")
		(32 "In15.Cu" signal "IN6")
		(34 "In16.Cu" signal "GND7")
		(2 "B.Cu" signal "BOTTOM")
		(9 "F.Adhes" user "F.Adhesive")
		(11 "B.Adhes" user "B.Adhesive")
		(13 "F.Paste" user "Package Geometry/Pastemask Top")
		(15 "B.Paste" user "Package Geometry/Pastemask Bottom")
		(5 "F.SilkS" user "Ref Des/Silkscreen Top")
		(7 "B.SilkS" user "Ref Des/Silkscreen Bottom")
		(1 "F.Mask" user "Board Geometry/Soldermask Top")
		(3 "B.Mask" user "Board Geometry/Soldermask Bottom")
		(17 "Dwgs.User" user "User.Drawings")
		(19 "Cmts.User" user "User.Comments")
		(21 "Eco1.User" user "User.Eco1")
		(23 "Eco2.User" user "User.Eco2")
		(25 "Edge.Cuts" user "Board Geometry/Outline")
		(27 "Margin" user)
		(31 "F.CrtYd" user "Package Geometry/Place Bound Top")
		(29 "B.CrtYd" user "Package Geometry/Place Bound Bottom")
		(35 "F.Fab" user "Ref Des/Assembly Top")
		(33 "B.Fab" user "Ref Des/Assembly Bottom")
	)
	(footprint ""
		(layer "F.Cu")
		(at 355.236018 -245.634002 -90)
		(property "Reference" "C991"
			(at 0 0 270)
			(layer "F.SilkS")
			(hide yes)
			(effects
				(font
					(size 1.27 1.27)
				)
			)
		)
		(property "Value" ""
			(at 0 0 270)
			(layer "F.Fab")
			(effects
				(font
					(size 1.27 1.27)
				)
			)
		)
		(duplicate_pad_numbers_are_jumpers no)
		(fp_line
			(start -0.7874 0.4064)
			(end -0.7874 -0.4064)
			(stroke
				(width 0.1524)
				(type default)
			)
			(layer "F.SilkS")
		)
		(fp_line
			(start 0.7874 0.4064)
			(end -0.7874 0.4064)
			(stroke
				(width 0.1524)
				(type default)
			)
			(layer "F.SilkS")
		)
		(fp_line
			(start -0.7874 -0.4064)
			(end 0.7874 -0.4064)
			(stroke
				(width 0.1524)
				(type default)
			)
			(layer "F.SilkS")
		)
		(fp_line
			(start 0.7874 -0.4064)
			(end 0.7874 0.4064)
			(stroke
				(width 0.1524)
				(type default)
			)
			(layer "F.SilkS")
		)
		(fp_line
			(start -0.67945 0.3048)
			(end -0.67945 -0.305054)
			(stroke
				(width 0.1)
				(type default)
			)
			(layer "F.Fab")
		)
		(fp_line
			(start -0.12065 0.3048)
			(end -0.67945 0.3048)
			(stroke
				(width 0.1)
				(type default)
			)
			(layer "F.Fab")
		)
		(fp_line
			(start 0.120396 0.3048)
			(end 0.120396 0.2794)
			(stroke
				(width 0.1)
				(type default)
			)
			(layer "F.Fab")
		)
		(fp_line
			(start 0.67945 0.3048)
			(end 0.120396 0.3048)
			(stroke
				(width 0.1)
				(type default)
			)
			(layer "F.Fab")
		)
		(fp_line
			(start -0.12065 0.2794)
			(end -0.12065 0.3048)
			(stroke
				(width 0.1)
				(type default)
			)
			(layer "F.Fab")
		)
		(fp_line
			(start 0.120396 0.2794)
			(end -0.12065 0.2794)
			(stroke
				(width 0.1)
				(type default)
			)
			(layer "F.Fab")
		)
		(fp_line
			(start -0.12065 -0.2794)
			(end 0.12065 -0.2794)
			(stroke
				(width 0.1)
				(type default)
			)
			(layer "F.Fab")
		)
		(fp_line
			(start 0.12065 -0.2794)
			(end 0.12065 -0.3048)
			(stroke
				(width 0.1)
				(type default)
			)
			(layer "F.Fab")
		)
		(fp_line
			(start 0.12065 -0.3048)
			(end 0.67945 -0.3048)
			(stroke
				(width 0.1)
				(type default)
			)
			(layer "F.Fab")
		)
		(fp_line
			(start 0.67945 -0.3048)
			(end 0.67945 0.3048)
			(stroke
				(width 0.1)
				(type default)
			)
			(layer "F.Fab")
		)
		(fp_line
			(start -0.67945 -0.305054)
			(end -0.12065 -0.305054)
			(stroke
				(width 0.1)
				(type default)
			)
			(layer "F.Fab")
		)
		(fp_line
			(start -0.12065 -0.305054)
			(end -0.12065 -0.2794)
			(stroke
				(width 0.1)
				(type default)
			)
			(layer "F.Fab")
		)
		(pad "1" smd circle
			(at -0.40005 0 270)
			(size 0 0)
			(layers "F.Cu" "F.Mask" "F.Paste")
			(net "PVCCIN_CPU0")
		)
		(pad "2" smd circle
			(at 0.40005 0 270)
			(size 0 0)
			(layers "F.Cu" "F.Mask" "F.Paste")
			(net "GND")
		)
	)
	(footprint ""
		(layer "F.Cu")
		(at 15.436596 -393.215876 180)
		(property "Reference" "R3276"
			(at 0 0 180)
			(layer "F.SilkS")
			(hide yes)
			(effects
				(font
					(size 1.27 1.27)
				)
			)
		)
		(property "Value" ""
			(at 0 0 180)
			(layer "F.Fab")
			(effects
				(font
					(size 1.27 1.27)
				)
			)
		)
		(duplicate_pad_numbers_are_jumpers no)
		(fp_line
			(start 0.7874 0.4064)
			(end -0.7874 0.4064)
			(stroke
				(width 0.1524)
				(type default)
			)
			(layer "F.SilkS")
		)
		(fp_line
			(start 0.7874 -0.4064)
			(end 0.7874 0.4064)
			(stroke
				(width 0.1524)
				(type default)
			)
			(layer "F.SilkS")
		)
		(fp_line
			(start -0.7874 0.4064)
			(end -0.7874 -0.4064)
			(stroke
				(width 0.1524)
				(type default)
			)
			(layer "F.SilkS")
		)
		(fp_line
			(start -0.7874 -0.4064)
			(end 0.7874 -0.4064)
			(stroke
				(width 0.1524)
				(type default)
			)
			(layer "F.SilkS")
		)
		(fp_line
			(start 0.67945 0.3048)
			(end 0.120396 0.3048)
			(stroke
				(width 0.1)
				(type default)
			)
			(layer "F.Fab")
		)
		(fp_line
			(start 0.67945 -0.3048)
			(end 0.67945 0.3048)
			(stroke
				(width 0.1)
				(type default)
			)
			(layer "F.Fab")
		)
		(fp_line
			(start 0.12065 -0.2794)
			(end 0.12065 -0.3048)
			(stroke
				(width 0.1)
				(type default)
			)
			(layer "F.Fab")
		)
		(fp_line
			(start 0.12065 -0.3048)
			(end 0.67945 -0.3048)
			(stroke
				(width 0.1)
				(type default)
			)
			(layer "F.Fab")
		)
		(fp_line
			(start 0.120396 0.3048)
			(end 0.120396 0.2794)
			(stroke
				(width 0.1)
				(type default)
			)
			(layer "F.Fab")
		)
		(fp_line
			(start 0.120396 0.2794)
			(end -0.12065 0.2794)
			(stroke
				(width 0.1)
				(type default)
			)
			(layer "F.Fab")
		)
		(fp_line
			(start -0.12065 0.3048)
			(end -0.67945 0.3048)
			(stroke
				(width 0.1)
				(type default)
			)
			(layer "F.Fab")
		)
		(fp_line
			(start -0.12065 0.2794)
			(end -0.12065 0.3048)
			(stroke
				(width 0.1)
				(type default)
			)
			(layer "F.Fab")
		)
		(fp_line
			(start -0.12065 -0.2794)
			(end 0.12065 -0.2794)
			(stroke
				(width 0.1)
				(type default)
			)
			(layer "F.Fab")
		)
		(fp_line
			(start -0.12065 -0.305054)
			(end -0.12065 -0.2794)
			(stroke
				(width 0.1)
				(type default)
			)
			(layer "F.Fab")
		)
		(fp_line
			(start -0.67945 0.3048)
			(end -0.67945 -0.305054)
			(stroke
				(width 0.1)
				(type default)
			)
			(layer "F.Fab")
		)
		(fp_line
			(start -0.67945 -0.305054)
			(end -0.12065 -0.305054)
			(stroke
				(width 0.1)
				(type default)
			)
			(layer "F.Fab")
		)
		(pad "1" smd circle
			(at -0.40005 0 180)
			(size 0 0)
			(layers "F.Cu" "F.Mask" "F.Paste")
			(net "FM_P2E_FGA")
		)
		(pad "2" smd circle
			(at 0.40005 0 180)
			(size 0 0)
			(layers "F.Cu" "F.Mask" "F.Paste")
			(net "GND")
		)
	)
)
